FILE_TYPE = CONNECTIVITY;
{Allegro Design Entry HDL 17.2-2016 S081 (4005846) 1/11/2022}
"PAGE_NUMBER" = 25;
0"NC";
1"P3V3_AUX\g";
2"P3V3_AUX\g";
3"P3V3_AUX\g";
4"P3V3_AUX\g";
5"P3V3_AUX\g";
6"P3V3_AUX\g";
7"GND\g";
8"GND\g";
9"GND\g";
10"GND\g";
11"GND\g";
12"GND\g";
13"GND\g";
14"RST_SPI_FLASH_BUF_R3_N";
15"FLASH_R_WP_STATUS";
16"FLASH_WP_STATUS";
17"RST_SPI_FLASH_R_N";
18"RST_SPI_FLASH_BUF_N";
19"SPI_BMC_BT_WP1_N_R";
20"SPI_BMC_BT_WP0_N_R";
21"FLASH_LATCH_Q_N_R2";
22"FLASH_LATCH_Q_N_R1";
23"FLASH_LATCH_Q_N_R";
24"NC_U55_P1";
25"BMC_RSTIND_N";
26"RD_N";
27"FM_FLASH_LATCH_N";
28"FLASH_LATCH_CP";
29"PU_J1_P1";
30"FM_FLASH_LATCH_N";
31"NC_J1_P3";
32"RST_SPI_FLASH_N";
33"FLASH_LATCH_D";
34"NC_U54_P1";
%"UNIVERSAL_POWER"
"1","(350,4100)","0","logical_power","I135";
;
HDL_POWER"P3V3_AUX"
CDS_LIB"logical_power";
"A"5;
%"74LVC1G74DP"
"1","(3075,3500)","0","pure_quanta","I138";
;
PART_NUMBER"AL1G0074K01"
VALUE"74LVC1G74DP"
MATERIAL"IC"
PART_TYPE"SMLF"
CDS_LMAN_SYM_OUTLINE"-200,300,200,-300"
NEEDS_NO_SIZE"TRUE"
CDS_LIB"pure_quanta"
$LOCATION"U54"
CDS_LOCATION"U54"
$SEC"1"
CDS_SEC"1";
"Q"
$PN"5"34;
"SD_N \B"
$PN"7"27;
"RD_N \B"
$PN"6"26;
"VCC"
$PN"8"2;
"GND"
$PN"4"12;
"Q_N \B"
$PN"3"23;
"D"
$PN"2"33;
"CP"
$PN"1"28;
%"Q_RES"
"1","(2000,3600)","0","pure_quanta","I142";
;
PART_NUMBER"CS00002JB13"
VALUE"0"
PACK_TYPE"0402LF"
TOLERANCE"5%"
WATTAGE"1/16W"
MATERIAL"CHIP"
CDS_LIB"pure_quanta"
$LOCATION"R182"
CDS_LOCATION"R182"
$SEC"1"
CDS_SEC"1";
"B"
$PN"2"33;
"A"
$PN"1"13;
%"Q_RES"
"1","(2000,3500)","0","pure_quanta","I143";
;
MATERIAL"CHIP"
VALUE"0"
PART_NUMBER"CS00002JB13"
CDS_LIB"pure_quanta"
PACK_TYPE"0402LF"
WATTAGE"1/16W"
TOLERANCE"5%"
$LOCATION"R545"
CDS_LOCATION"R545"
$SEC"1"
CDS_SEC"1";
"B"
$PN"2"28;
"A"
$PN"1"13;
%"UNIVERSAL_GND"
"1","(1350,3425)","2","logical_power","I144";
;
CDS_LIB"logical_power"
HDL_POWER"GND";
"A"13;
%"UNIVERSAL_POWER"
"1","(2375,4225)","0","logical_power","I145";
;
HDL_POWER"P3V3_AUX"
CDS_LIB"logical_power";
"A"2;
%"Q_CAP"
"1","(2375,4000)","0","pure_quanta","I146";
;
VALUE"0.1UF"
PACK_TYPE"0402"
VOLTAGE"25V"
PART_NUMBER"CH4104K1B00"
MATERIAL"X7R"
TOLERANCE"10%"
CDS_LIB"pure_quanta"
$LOCATION"C312"
CDS_LOCATION"C312"
$SEC"1"
CDS_SEC"1";
"B"
$PN"2"11;
"A"
$PN"1"2;
%"UNIVERSAL_GND"
"1","(2375,3775)","2","logical_power","I147";
;
CDS_LIB"logical_power"
HDL_POWER"GND";
"A"11;
%"Q_RES"
"2","(5000,3150)","0","pure_quanta","I149";
;
PART_NUMBER"CS00002JB13"
PACK_TYPE"0402LF"
WATTAGE"1/16W"
MATERIAL"CHIP"
VALUE"0"
TOLERANCE"5%"
CDS_LIB"pure_quanta"
$LOCATION"R560"
CDS_LOCATION"R560"
$SEC"1"
CDS_SEC"1";
"A"
$PN"1"22;
"B"
$PN"2"21;
%"SN74LVC1G14DCKR"
"1","(4275,2600)","2","pure_quanta","I150";
;
MATERIAL"IC"
VALUE"SN74LVC1G14DCKR"
PACK_TYPE"SMLF"
PART_NUMBER"AL001G14017"
NEEDS_NO_SIZE"TRUE"
CDS_LIB"pure_quanta"
$LOCATION"U55"
CDS_LOCATION"U55"
$SEC"1"
CDS_SEC"1";
"NC"
$PN"1"24;
"Y"
$PN"4"15;
"GND"
$PN"3"10;
"A"
$PN"2"21;
"VCC"
$PN"5"3;
%"UNIVERSAL_POWER"
"1","(3675,3275)","0","logical_power","I153";
;
HDL_POWER"P3V3_AUX"
CDS_LIB"logical_power";
"A"3;
%"Q_CAP"
"1","(3675,3000)","0","pure_quanta","I154";
;
VOLTAGE"25V"
VALUE"0.1UF"
MATERIAL"X7R"
TOLERANCE"10%"
PART_NUMBER"CH4104K1B00"
PACK_TYPE"0402"
CDS_LIB"pure_quanta"
$LOCATION"C313"
CDS_LOCATION"C313"
$SEC"1"
CDS_SEC"1";
"B"
$PN"2"9;
"A"
$PN"1"3;
%"UNIVERSAL_GND"
"1","(3675,2825)","2","logical_power","I155";
;
HDL_POWER"GND"
CDS_LIB"logical_power";
"A"9;
%"Q_RES"
"2","(3100,2925)","0","pure_quanta","I156";
;
MATERIAL"EMPTY"
TOLERANCE"1%"
VALUE"4.7K"
CDS_LIB"pure_quanta"
PART_NUMBER"CS24702FB10"
WATTAGE"1/16W"
PACK_TYPE"0402LF"
$LOCATION"R554"
CDS_LOCATION"R554"
$SEC"1"
CDS_SEC"1";
"A"
$PN"1"3;
"B"
$PN"2"15;
%"UNIVERSAL_GND"
"1","(3450,3175)","2","logical_power","I157";
;
CDS_LIB"logical_power"
HDL_POWER"GND";
"A"12;
%"UNIVERSAL_GND"
"1","(3850,2425)","2","logical_power","I158";
;
HDL_POWER"GND"
CDS_LIB"logical_power";
"A"10;
%"UNIVERSAL_POWER"
"1","(3900,1725)","0","logical_power","I166";
;
HDL_POWER"P3V3_AUX"
CDS_LIB"logical_power";
"A"1;
%"SCONN3_212H9103GBR1"
"1","(4500,1250)","0","pure_quanta","I169";
;
PART_NUMBER"DFHD03MS161"
VALUE"SCONN3_212-H91-03GBR1"
MATERIAL"IO"
PART_TYPE"SMLF"
NEEDS_NO_SIZE"TRUE"
CDS_LMAN_SYM_OUTLINE"-50,100,50,-100"
CDS_LIB"pure_quanta"
LOCATION"J1"
$SEC"1"
CDS_SEC"1";
"1"
$PN"1"29;
"2"
$PN"2"21;
"3"
$PN"3"31;
%"Q_RES"
"2","(350,3900)","0","pure_quanta","I170";
;
WATTAGE"1/16W"
MATERIAL"CHIP"
PACK_TYPE"0402LF"
TOLERANCE"1%"
VALUE"4.7K"
PART_NUMBER"CS24702FB06"
CDS_LIB"pure_quanta"
LOCATION"R181"
$SEC"1"
CDS_SEC"1";
"A"
$PN"1"5;
"B"
$PN"2"30;
%"Q_RES"
"2","(3900,1525)","0","pure_quanta","I171";
;
PACK_TYPE"0402LF"
MATERIAL"CHIP"
WATTAGE"1/16W"
VALUE"4.7K"
TOLERANCE"1%"
PART_NUMBER"CS24702FB06"
CDS_LIB"pure_quanta"
LOCATION"R592"
$SEC"1"
CDS_SEC"1";
"A"
$PN"1"1;
"B"
$PN"2"29;
%"Q_RES"
"1","(2275,3300)","0","pure_quanta","I172";
;
VALUE"33.2"
MATERIAL"CHIP"
CDS_LIB"pure_quanta"
TOLERANCE"1%"
PART_NUMBER"CS03322FB03"
PACK_TYPE"0402LF"
WATTAGE"1/16W"
LOCATION"R548"
$SEC"1"
CDS_SEC"1";
"B"
$PN"2"26;
"A"
$PN"1"25;
%"Q_RES"
"1","(2900,2600)","0","pure_quanta","I173";
;
MATERIAL"CHIP"
VALUE"33.2"
CDS_LIB"pure_quanta"
WATTAGE"1/16W"
PACK_TYPE"0402LF"
PART_NUMBER"CS03322FB03"
TOLERANCE"1%"
LOCATION"R551"
$SEC"1"
CDS_SEC"1";
"B"
$PN"2"15;
"A"
$PN"1"16;
%"Q_RES"
"1","(4200,3550)","0","pure_quanta","I174";
;
MATERIAL"CHIP"
VALUE"33.2"
WATTAGE"1/16W"
PACK_TYPE"0402LF"
PART_NUMBER"CS03322FB03"
TOLERANCE"1%"
CDS_LIB"pure_quanta"
LOCATION"R555"
$SEC"1"
CDS_SEC"1";
"B"
$PN"2"22;
"A"
$PN"1"23;
%"Q_RES"
"1","(3425,1900)","0","pure_quanta","I175";
;
VALUE"33.2"
MATERIAL"CHIP"
WATTAGE"1/16W"
PACK_TYPE"0402LF"
PART_NUMBER"CS03322FB03"
TOLERANCE"1%"
CDS_LIB"pure_quanta"
LOCATION"R556"
$SEC"1"
CDS_SEC"1";
"B"
$PN"2"21;
"A"
$PN"1"19;
%"Q_RES"
"1","(3425,1825)","0","pure_quanta","I176";
;
MATERIAL"CHIP"
VALUE"33.2"
WATTAGE"1/16W"
PACK_TYPE"0402LF"
PART_NUMBER"CS03322FB03"
TOLERANCE"1%"
CDS_LIB"pure_quanta"
LOCATION"R559"
$SEC"1"
CDS_SEC"1";
"B"
$PN"2"21;
"A"
$PN"1"20;
%"UNIVERSAL_POWER"
"1","(2875,-425)","0","logical_power","I2";
;
HDL_POWER"P3V3_AUX"
CDS_LIB"logical_power";
"A"4;
%"Q_RES"
"2","(2875,-675)","2","pure_quanta","I3";
;
VALUE"4.7K"
TOLERANCE"1%"
MATERIAL"CHIP"
PART_NUMBER"CS24702FB06"
PACK_TYPE"0402LF"
CDS_LIB"pure_quanta"
WATTAGE"1/16W"
LOCATION"R563"
$SEC"1"
CDS_SEC"1";
"A"
$PN"1"4;
"B"
$PN"2"18;
%"SN74LVC1G07DCKR"
"1","(450,-950)","0","pure_quanta","I61";
;
VALUE"SN74LVC1G07DCKR"
PART_NUMBER"AL1G0007016"
MATERIAL"IC"
PART_TYPE"SMLF"
CDS_LIB"pure_quanta"
CDS_LMAN_SYM_OUTLINE"-125,150,125,-150"
NEEDS_NO_SIZE"TRUE"
LOCATION"U44"
$SEC"1"
CDS_SEC"1";
"NC1"
$PN"1"0;
"Y"
$PN"4"14;
"GND"
$PN"3"7;
"A"
$PN"2"17;
"VCC"
$PN"5"6;
%"UNIVERSAL_GND"
"1","(125,-1250)","0","logical_power","I62";
;
CDS_LIB"logical_power"
HDL_POWER"GND";
"A"7;
%"UNIVERSAL_GND"
"1","(-25,-650)","0","logical_power","I64";
;
CDS_LIB"logical_power"
HDL_POWER"GND";
"A"8;
%"Q_CAP"
"1","(-25,-450)","0","pure_quanta","I65";
;
VALUE"0.1UF"
MATERIAL"X7R"
PACK_TYPE"0402"
TOLERANCE"10%"
VOLTAGE"25V"
PART_NUMBER"CH4104K1B00"
SEC_TYPE"0402"
CDS_LIB"pure_quanta"
LOCATION"C304"
SEC"1";
"B"
$PN"2"8;
"A"
$PN"1"6;
%"Q_RES"
"1","(-925,-950)","0","pure_quanta","I67";
;
MATERIAL"CHIP"
VALUE"33.2"
TOLERANCE"1%"
PART_NUMBER"CS03322FB03"
PACK_TYPE"0402LF"
WATTAGE"1/16W"
CDS_LIB"pure_quanta"
LOCATION"R752"
$SEC"1"
CDS_SEC"1";
"B"
$PN"2"17;
"A"
$PN"1"32;
%"UNIVERSAL_POWER"
"1","(-200,-175)","0","logical_power","I72";
;
HDL_POWER"P3V3_AUX"
CDS_LIB"logical_power";
"A"6;
%"Q_RES"
"1","(1825,-950)","0","pure_quanta","I73";
;
MATERIAL"CHIP"
VALUE"33.2"
TOLERANCE"1%"
PART_NUMBER"CS03322FB03"
PACK_TYPE"0402LF"
WATTAGE"1/16W"
CDS_LIB"pure_quanta"
LOCATION"R827"
$SEC"1"
CDS_SEC"1";
"B"
$PN"2"18;
"A"
$PN"1"14;
END.
